# S9S_MB_2U (Grand Teton) — schematic netlist excerpt (pin names and nets, part order shuffled) for the footprints in the layout excerpt that follows; sources: Cadence DE-HDL packaged netlist, KiCad conversion of 03242023_DA0F0TMBIJ0_F0T_Motherboard_J_brd_V01_OCP.brd

PL2  Q_INDUCTOR  130NH/106A IND  pkg SMLF  page 272 : \1\ = SW_PVCCFA_EHV_FIVRA_CPU0_SW3 ; \2\ = PVCCFA_EHV_FIVRA_CPU0
R3153  Q_RES  1K 1% EMPTY  pkg 0402LF  page 164 : A = P3V3_AUX ; B = PD_SMB_OCP2_HP_ADD0

(kicad_pcb
	(version 20260206)
	(generator "pcbnew")
	(generator_version "10.0")
	(general
		(thickness 1.6)
		(legacy_teardrops no)
	)
	(paper "A4")
	(title_block
		(title "03242023_DA0F0TMBIJ0_F0T_Motherboard_J_brd_V01_OCP.brd")
		(comment 1 "Grand Teton / footprints 626-627 of 6105")
	)
	(layers
		(0 "F.Cu" signal "TOP")
		(4 "In1.Cu" signal "GND")
		(6 "In2.Cu" signal "IN1")
		(8 "In3.Cu" signal "GND1")
		(10 "In4.Cu" signal "IN2")
		(12 "In5.Cu" signal "GND2")
		(14 "In6.Cu" signal "IN3")
		(16 "In7.Cu" signal "GND3")
		(18 "In8.Cu" signal "VCC")
		(20 "In9.Cu" signal "VCC1")
		(22 "In10.Cu" signal "GND4")
		(24 "In11.Cu" signal "IN4")
		(26 "In12.Cu" signal "GND5")
		(28 "In13.Cu" signal "IN5")
		(30 "In14.Cu" signal "GND6")
		(32 "In15.Cu" signal "IN6")
		(34 "In16.Cu" signal "GND7")
		(2 "B.Cu" signal "BOTTOM")
		(9 "F.Adhes" user "F.Adhesive")
		(11 "B.Adhes" user "B.Adhesive")
		(13 "F.Paste" user "Package Geometry/Pastemask Top")
		(15 "B.Paste" user "Package Geometry/Pastemask Bottom")
		(5 "F.SilkS" user "Ref Des/Silkscreen Top")
		(7 "B.SilkS" user "Ref Des/Silkscreen Bottom")
		(1 "F.Mask" user "Board Geometry/Soldermask Top")
		(3 "B.Mask" user "Board Geometry/Soldermask Bottom")
		(17 "Dwgs.User" user "User.Drawings")
		(19 "Cmts.User" user "User.Comments")
		(21 "Eco1.User" user "User.Eco1")
		(23 "Eco2.User" user "User.Eco2")
		(25 "Edge.Cuts" user "Board Geometry/Outline")
		(27 "Margin" user)
		(31 "F.CrtYd" user "Package Geometry/Place Bound Top")
		(29 "B.CrtYd" user "Package Geometry/Place Bound Bottom")
		(35 "F.Fab" user "Ref Des/Assembly Top")
		(33 "B.Fab" user "Ref Des/Assembly Bottom")
	)
	(footprint ""
		(layer "F.Cu")
		(at 425.846748 -353.312984 -90)
		(property "Reference" "PL2"
			(at -3.919474 -4.335272 0)
			(unlocked yes)
			(layer "F.SilkS")
			(effects
				(font
					(size 0.7874 0.5842)
					(thickness 0.1524)
				)
				(justify left)
			)
		)
		(property "Value" ""
			(at 0 0 270)
			(layer "F.Fab")
			(effects
				(font
					(size 1.27 1.27)
				)
			)
		)
		(duplicate_pad_numbers_are_jumpers no)
		(fp_line
			(start -4.99999 3.750056)
			(end -4.99999 2.2479)
			(stroke
				(width 0.1524)
				(type default)
			)
			(layer "F.SilkS")
		)
		(fp_line
			(start 0 3.750056)
			(end -4.99999 3.750056)
			(stroke
				(width 0.1524)
				(type default)
			)
			(layer "F.SilkS")
		)
		(fp_line
			(start 4.99999 3.750056)
			(end 0 3.750056)
			(stroke
				(width 0.1524)
				(type default)
			)
			(layer "F.SilkS")
		)
		(fp_line
			(start 4.99999 2.2352)
			(end 4.99999 3.750056)
			(stroke
				(width 0.1524)
				(type default)
			)
			(layer "F.SilkS")
		)
		(fp_line
			(start -4.99999 -2.2479)
			(end -4.99999 -3.750056)
			(stroke
				(width 0.1524)
				(type default)
			)
			(layer "F.SilkS")
		)
		(fp_line
			(start -4.99999 -3.750056)
			(end 4.99999 -3.750056)
			(stroke
				(width 0.1524)
				(type default)
			)
			(layer "F.SilkS")
		)
		(fp_line
			(start 4.99999 -3.750056)
			(end 4.99999 -2.2479)
			(stroke
				(width 0.1524)
				(type default)
			)
			(layer "F.SilkS")
		)
		(fp_line
			(start -4.99999 3.750056)
			(end -4.99999 -3.750056)
			(stroke
				(width 0.1)
				(type default)
			)
			(layer "F.Fab")
		)
		(fp_line
			(start 0 3.750056)
			(end -4.99999 3.750056)
			(stroke
				(width 0.1)
				(type default)
			)
			(layer "F.Fab")
		)
		(fp_line
			(start 4.99999 3.750056)
			(end 0 3.750056)
			(stroke
				(width 0.1)
				(type default)
			)
			(layer "F.Fab")
		)
		(fp_line
			(start -4.99999 -3.750056)
			(end 4.99999 -3.750056)
			(stroke
				(width 0.1)
				(type default)
			)
			(layer "F.Fab")
		)
		(fp_line
			(start 4.99999 -3.750056)
			(end 4.99999 3.750056)
			(stroke
				(width 0.1)
				(type default)
			)
			(layer "F.Fab")
		)
		(pad "1" smd rect
			(at -3.299968 0 270)
			(size 3.302 4.2164)
			(layers "F.Cu" "F.Mask" "F.Paste")
			(net "SW_PVCCFA_EHV_FIVRA_CPU0_SW3")
		)
		(pad "2" smd rect
			(at 3.299968 0 270)
			(size 3.302 4.2164)
			(layers "F.Cu" "F.Mask" "F.Paste")
			(net "PVCCFA_EHV_FIVRA_CPU0")
		)
	)
	(footprint ""
		(layer "F.Cu")
		(at 147.08378 -124.005848 180)
		(property "Reference" "R3153"
			(at 0 0 180)
			(layer "F.SilkS")
			(hide yes)
			(effects
				(font
					(size 1.27 1.27)
				)
			)
		)
		(property "Value" ""
			(at 0 0 180)
			(layer "F.Fab")
			(effects
				(font
					(size 1.27 1.27)
				)
			)
		)
		(duplicate_pad_numbers_are_jumpers no)
		(fp_line
			(start 0.7874 0.4064)
			(end -0.7874 0.4064)
			(stroke
				(width 0.1524)
				(type default)
			)
			(layer "F.SilkS")
		)
		(fp_line
			(start 0.7874 -0.4064)
			(end 0.7874 0.4064)
			(stroke
				(width 0.1524)
				(type default)
			)
			(layer "F.SilkS")
		)
		(fp_line
			(start -0.7874 0.4064)
			(end -0.7874 -0.4064)
			(stroke
				(width 0.1524)
				(type default)
			)
			(layer "F.SilkS")
		)
		(fp_line
			(start -0.7874 -0.4064)
			(end 0.7874 -0.4064)
			(stroke
				(width 0.1524)
				(type default)
			)
			(layer "F.SilkS")
		)
		(fp_line
			(start 0.67945 0.3048)
			(end 0.120396 0.3048)
			(stroke
				(width 0.1)
				(type default)
			)
			(layer "F.Fab")
		)
		(fp_line
			(start 0.67945 -0.3048)
			(end 0.67945 0.3048)
			(stroke
				(width 0.1)
				(type default)
			)
			(layer "F.Fab")
		)
		(fp_line
			(start 0.12065 -0.2794)
			(end 0.12065 -0.3048)
			(stroke
				(width 0.1)
				(type default)
			)
			(layer "F.Fab")
		)
		(fp_line
			(start 0.12065 -0.3048)
			(end 0.67945 -0.3048)
			(stroke
				(width 0.1)
				(type default)
			)
			(layer "F.Fab")
		)
		(fp_line
			(start 0.120396 0.3048)
			(end 0.120396 0.2794)
			(stroke
				(width 0.1)
				(type default)
			)
			(layer "F.Fab")
		)
		(fp_line
			(start 0.120396 0.2794)
			(end -0.12065 0.2794)
			(stroke
				(width 0.1)
				(type default)
			)
			(layer "F.Fab")
		)
		(fp_line
			(start -0.12065 0.3048)
			(end -0.67945 0.3048)
			(stroke
				(width 0.1)
				(type default)
			)
			(layer "F.Fab")
		)
		(fp_line
			(start -0.12065 0.2794)
			(end -0.12065 0.3048)
			(stroke
				(width 0.1)
				(type default)
			)
			(layer "F.Fab")
		)
		(fp_line
			(start -0.12065 -0.2794)
			(end 0.12065 -0.2794)
			(stroke
				(width 0.1)
				(type default)
			)
			(layer "F.Fab")
		)
		(fp_line
			(start -0.12065 -0.305054)
			(end -0.12065 -0.2794)
			(stroke
				(width 0.1)
				(type default)
			)
			(layer "F.Fab")
		)
		(fp_line
			(start -0.67945 0.3048)
			(end -0.67945 -0.305054)
			(stroke
				(width 0.1)
				(type default)
			)
			(layer "F.Fab")
		)
		(fp_line
			(start -0.67945 -0.305054)
			(end -0.12065 -0.305054)
			(stroke
				(width 0.1)
				(type default)
			)
			(layer "F.Fab")
		)
		(pad "1" smd circle
			(at -0.40005 0 180)
			(size 0 0)
			(layers "F.Cu" "F.Mask" "F.Paste")
			(net "P3V3_AUX")
		)
		(pad "2" smd circle
			(at 0.40005 0 180)
			(size 0 0)
			(layers "F.Cu" "F.Mask" "F.Paste")
			(net "PD_SMB_OCP2_HP_ADD0")
		)
	)
)
